# T6G (Grand Teton) — schematic netlist excerpt (pin names and nets, part order shuffled) for the footprints in the layout excerpt that follows; sources: Cadence DE-HDL packaged netlist, KiCad conversion of 04192023_DAF0TMB3IC0_F0TG_MB_C_brd_V02_OCP.brd

PC345_9  Q_CAP  0.1UF 25V 10% X7R  pkg 0402  page 216 : A = PVDDCR_CPU0_P1_VCCS ; B = GND
R3754  Q_RES  0 5% CHIP  pkg 0402LF  page 236 : A = SMB_INA230_2_3V3AUX_SCL_R ; B = SMB_INA230_2_3V3AUX_SCL_R1

(kicad_pcb
	(version 20260206)
	(generator "pcbnew")
	(generator_version "10.0")
	(general
		(thickness 1.6)
		(legacy_teardrops no)
	)
	(paper "A4")
	(title_block
		(title "04192023_DAF0TMB3IC0_F0TG_MB_C_brd_V02_OCP.brd")
		(comment 1 "Grand Teton / footprints 4070-4071 of 8354")
	)
	(layers
		(0 "F.Cu" signal "TOP")
		(4 "In1.Cu" signal "GND")
		(6 "In2.Cu" signal "IN1")
		(8 "In3.Cu" signal "GND1")
		(10 "In4.Cu" signal "IN2")
		(12 "In5.Cu" signal "GND2")
		(14 "In6.Cu" signal "IN3")
		(16 "In7.Cu" signal "GND3")
		(18 "In8.Cu" signal "VCC")
		(20 "In9.Cu" signal "VCC1")
		(22 "In10.Cu" signal "GND4")
		(24 "In11.Cu" signal "IN4")
		(26 "In12.Cu" signal "GND5")
		(28 "In13.Cu" signal "IN5")
		(30 "In14.Cu" signal "GND6")
		(32 "In15.Cu" signal "IN6")
		(34 "In16.Cu" signal "GND7")
		(2 "B.Cu" signal "BOTTOM")
		(9 "F.Adhes" user "F.Adhesive")
		(11 "B.Adhes" user "B.Adhesive")
		(13 "F.Paste" user "Package Geometry/Pastemask Top")
		(15 "B.Paste" user "Package Geometry/Pastemask Bottom")
		(5 "F.SilkS" user "Ref Des/Silkscreen Top")
		(7 "B.SilkS" user "Ref Des/Silkscreen Bottom")
		(1 "F.Mask" user "Board Geometry/Soldermask Top")
		(3 "B.Mask" user "Board Geometry/Soldermask Bottom")
		(17 "Dwgs.User" user "User.Drawings")
		(19 "Cmts.User" user "User.Comments")
		(21 "Eco1.User" user "User.Eco1")
		(23 "Eco2.User" user "User.Eco2")
		(25 "Edge.Cuts" user "Board Geometry/Outline")
		(27 "Margin" user)
		(31 "F.CrtYd" user "Package Geometry/Place Bound Top")
		(29 "B.CrtYd" user "Package Geometry/Place Bound Bottom")
		(35 "F.Fab" user "Ref Des/Assembly Top")
		(33 "B.Fab" user "Ref Des/Assembly Bottom")
	)
	(footprint ""
		(layer "F.Cu")
		(at 214.43188 -50.637948 90)
		(property "Reference" "R3754"
			(at 0 0 90)
			(layer "F.SilkS")
			(hide yes)
			(effects
				(font
					(size 1.27 1.27)
				)
			)
		)
		(property "Value" ""
			(at 0 0 90)
			(layer "F.Fab")
			(effects
				(font
					(size 1.27 1.27)
				)
			)
		)
		(duplicate_pad_numbers_are_jumpers no)
		(fp_line
			(start 0.7874 -0.4064)
			(end 0.7874 0.4064)
			(stroke
				(width 0.1524)
				(type default)
			)
			(layer "F.SilkS")
		)
		(fp_line
			(start -0.7874 -0.4064)
			(end 0.7874 -0.4064)
			(stroke
				(width 0.1524)
				(type default)
			)
			(layer "F.SilkS")
		)
		(fp_line
			(start 0.7874 0.4064)
			(end -0.7874 0.4064)
			(stroke
				(width 0.1524)
				(type default)
			)
			(layer "F.SilkS")
		)
		(fp_line
			(start -0.7874 0.4064)
			(end -0.7874 -0.4064)
			(stroke
				(width 0.1524)
				(type default)
			)
			(layer "F.SilkS")
		)
		(fp_line
			(start -0.12065 -0.305054)
			(end -0.12065 -0.2794)
			(stroke
				(width 0.1)
				(type default)
			)
			(layer "F.Fab")
		)
		(fp_line
			(start -0.67945 -0.305054)
			(end -0.12065 -0.305054)
			(stroke
				(width 0.1)
				(type default)
			)
			(layer "F.Fab")
		)
		(fp_line
			(start 0.67945 -0.3048)
			(end 0.67945 0.3048)
			(stroke
				(width 0.1)
				(type default)
			)
			(layer "F.Fab")
		)
		(fp_line
			(start 0.12065 -0.3048)
			(end 0.67945 -0.3048)
			(stroke
				(width 0.1)
				(type default)
			)
			(layer "F.Fab")
		)
		(fp_line
			(start 0.12065 -0.2794)
			(end 0.12065 -0.3048)
			(stroke
				(width 0.1)
				(type default)
			)
			(layer "F.Fab")
		)
		(fp_line
			(start -0.12065 -0.2794)
			(end 0.12065 -0.2794)
			(stroke
				(width 0.1)
				(type default)
			)
			(layer "F.Fab")
		)
		(fp_line
			(start 0.120396 0.2794)
			(end -0.12065 0.2794)
			(stroke
				(width 0.1)
				(type default)
			)
			(layer "F.Fab")
		)
		(fp_line
			(start -0.12065 0.2794)
			(end -0.12065 0.3048)
			(stroke
				(width 0.1)
				(type default)
			)
			(layer "F.Fab")
		)
		(fp_line
			(start 0.67945 0.3048)
			(end 0.120396 0.3048)
			(stroke
				(width 0.1)
				(type default)
			)
			(layer "F.Fab")
		)
		(fp_line
			(start 0.120396 0.3048)
			(end 0.120396 0.2794)
			(stroke
				(width 0.1)
				(type default)
			)
			(layer "F.Fab")
		)
		(fp_line
			(start -0.12065 0.3048)
			(end -0.67945 0.3048)
			(stroke
				(width 0.1)
				(type default)
			)
			(layer "F.Fab")
		)
		(fp_line
			(start -0.67945 0.3048)
			(end -0.67945 -0.305054)
			(stroke
				(width 0.1)
				(type default)
			)
			(layer "F.Fab")
		)
		(pad "1" smd circle
			(at -0.40005 0 90)
			(size 0 0)
			(layers "F.Cu" "F.Mask" "F.Paste")
			(net "SMB_INA230_2_3V3AUX_SCL_R")
		)
		(pad "2" smd circle
			(at 0.40005 0 90)
			(size 0 0)
			(layers "F.Cu" "F.Mask" "F.Paste")
			(net "SMB_INA230_2_3V3AUX_SCL_R1")
		)
	)
	(footprint ""
		(layer "F.Cu")
		(at 135.118094 -151.67356 -90)
		(property "Reference" "PC345_9"
			(at 0 0 270)
			(layer "F.SilkS")
			(hide yes)
			(effects
				(font
					(size 1.27 1.27)
				)
			)
		)
		(property "Value" ""
			(at 0 0 270)
			(layer "F.Fab")
			(effects
				(font
					(size 1.27 1.27)
				)
			)
		)
		(duplicate_pad_numbers_are_jumpers no)
		(fp_line
			(start -0.7874 0.4064)
			(end -0.7874 -0.4064)
			(stroke
				(width 0.1524)
				(type default)
			)
			(layer "F.SilkS")
		)
		(fp_line
			(start 0.7874 0.4064)
			(end -0.7874 0.4064)
			(stroke
				(width 0.1524)
				(type default)
			)
			(layer "F.SilkS")
		)
		(fp_line
			(start -0.7874 -0.4064)
			(end 0.7874 -0.4064)
			(stroke
				(width 0.1524)
				(type default)
			)
			(layer "F.SilkS")
		)
		(fp_line
			(start 0.7874 -0.4064)
			(end 0.7874 0.4064)
			(stroke
				(width 0.1524)
				(type default)
			)
			(layer "F.SilkS")
		)
		(fp_line
			(start -0.67945 0.3048)
			(end -0.67945 -0.305054)
			(stroke
				(width 0.1)
				(type default)
			)
			(layer "F.Fab")
		)
		(fp_line
			(start -0.12065 0.3048)
			(end -0.67945 0.3048)
			(stroke
				(width 0.1)
				(type default)
			)
			(layer "F.Fab")
		)
		(fp_line
			(start 0.120396 0.3048)
			(end 0.120396 0.2794)
			(stroke
				(width 0.1)
				(type default)
			)
			(layer "F.Fab")
		)
		(fp_line
			(start 0.67945 0.3048)
			(end 0.120396 0.3048)
			(stroke
				(width 0.1)
				(type default)
			)
			(layer "F.Fab")
		)
		(fp_line
			(start -0.12065 0.2794)
			(end -0.12065 0.3048)
			(stroke
				(width 0.1)
				(type default)
			)
			(layer "F.Fab")
		)
		(fp_line
			(start 0.120396 0.2794)
			(end -0.12065 0.2794)
			(stroke
				(width 0.1)
				(type default)
			)
			(layer "F.Fab")
		)
		(fp_line
			(start -0.12065 -0.2794)
			(end 0.12065 -0.2794)
			(stroke
				(width 0.1)
				(type default)
			)
			(layer "F.Fab")
		)
		(fp_line
			(start 0.12065 -0.2794)
			(end 0.12065 -0.3048)
			(stroke
				(width 0.1)
				(type default)
			)
			(layer "F.Fab")
		)
		(fp_line
			(start 0.12065 -0.3048)
			(end 0.67945 -0.3048)
			(stroke
				(width 0.1)
				(type default)
			)
			(layer "F.Fab")
		)
		(fp_line
			(start 0.67945 -0.3048)
			(end 0.67945 0.3048)
			(stroke
				(width 0.1)
				(type default)
			)
			(layer "F.Fab")
		)
		(fp_line
			(start -0.67945 -0.305054)
			(end -0.12065 -0.305054)
			(stroke
				(width 0.1)
				(type default)
			)
			(layer "F.Fab")
		)
		(fp_line
			(start -0.12065 -0.305054)
			(end -0.12065 -0.2794)
			(stroke
				(width 0.1)
				(type default)
			)
			(layer "F.Fab")
		)
		(pad "1" smd circle
			(at -0.40005 0 270)
			(size 0 0)
			(layers "F.Cu" "F.Mask" "F.Paste")
			(net "PVDDCR_CPU0_P1_VCCS")
		)
		(pad "2" smd circle
			(at 0.40005 0 270)
			(size 0 0)
			(layers "F.Cu" "F.Mask" "F.Paste")
			(net "GND")
		)
	)
)
